FILE_TYPE=LIBRARY_PARTS;
primitive 'MX25L51245GMI10G';
  pin
    'NC_SIO3':
      PIN_NUMBER='(1)';
      BIDIRECTIONAL='TRUE';
      INPUT_LOAD='(-0.01,0.01)';
      OUTPUT_LOAD='(1.0,-1.0)';
    'VCC':
      PIN_NUMBER='(2)';
      PINUSE='POWER';
      NO_LOAD_CHECK='Both';
      NO_IO_CHECK='Both';
      NO_ASSERT_CHECK='TRUE';
      NO_DIR_CHECK='TRUE';
      ALLOW_CONNECT='TRUE';
    'RESET#':
      PIN_NUMBER='(3)';
      BIDIRECTIONAL='TRUE';
      INPUT_LOAD='(-0.01,0.01)';
      OUTPUT_LOAD='(1.0,-1.0)';
    'NC1':
      PIN_NUMBER='(4)';
      OUTPUT_TYPE='(TS,TS)';
      INPUT_LOAD='(-0.01,0.01)';
      OUTPUT_LOAD='(1.0,-1.0)';
    'DNU1':
      PIN_NUMBER='(5)';
      OUTPUT_TYPE='(TS,TS)';
      INPUT_LOAD='(-0.01,0.01)';
      OUTPUT_LOAD='(1.0,-1.0)';
    'DNU2':
      PIN_NUMBER='(6)';
      OUTPUT_TYPE='(TS,TS)';
      INPUT_LOAD='(-0.01,0.01)';
      OUTPUT_LOAD='(1.0,-1.0)';
    'CS#':
      PIN_NUMBER='(7)';
      BIDIRECTIONAL='TRUE';
      INPUT_LOAD='(-0.01,0.01)';
      OUTPUT_LOAD='(1.0,-1.0)';
    'SO_SIO1':
      PIN_NUMBER='(8)';
      BIDIRECTIONAL='TRUE';
      INPUT_LOAD='(-0.01,0.01)';
      OUTPUT_LOAD='(1.0,-1.0)';
    'WP#_SIO2':
      PIN_NUMBER='(9)';
      BIDIRECTIONAL='TRUE';
      INPUT_LOAD='(-0.01,0.01)';
      OUTPUT_LOAD='(1.0,-1.0)';
    'GND':
      PIN_NUMBER='(10)';
      PINUSE='POWER';
      NO_LOAD_CHECK='Both';
      NO_IO_CHECK='Both';
      NO_ASSERT_CHECK='TRUE';
      NO_DIR_CHECK='TRUE';
      ALLOW_CONNECT='TRUE';
    'DNU3':
      PIN_NUMBER='(11)';
      OUTPUT_TYPE='(TS,TS)';
      INPUT_LOAD='(-0.01,0.01)';
      OUTPUT_LOAD='(1.0,-1.0)';
    'DNU4':
      PIN_NUMBER='(12)';
      OUTPUT_TYPE='(TS,TS)';
      INPUT_LOAD='(-0.01,0.01)';
      OUTPUT_LOAD='(1.0,-1.0)';
    'NC2':
      PIN_NUMBER='(13)';
      OUTPUT_TYPE='(TS,TS)';
      INPUT_LOAD='(-0.01,0.01)';
      OUTPUT_LOAD='(1.0,-1.0)';
    'NC3':
      PIN_NUMBER='(14)';
      OUTPUT_TYPE='(TS,TS)';
      INPUT_LOAD='(-0.01,0.01)';
      OUTPUT_LOAD='(1.0,-1.0)';
    'SI_SIO0':
      PIN_NUMBER='(15)';
      BIDIRECTIONAL='TRUE';
      INPUT_LOAD='(-0.01,0.01)';
      OUTPUT_LOAD='(1.0,-1.0)';
    'SCLK':
      PIN_NUMBER='(16)';
      INPUT_LOAD='(-0.01,0.01)';
  end_pin;
  body
    PART_NAME='MX25L51245GMI10G';
    BODY_NAME='MX25L51245GMI10G';
    PHYS_DES_PREFIX='U';
    CLASS='IC';
  end_body;
end_primitive;

END.
